FILE_TYPE = MULTI_PHYS_TABLE;

PART '74LVC1G07_SC70_5'
CLASS=IC

{========================================================================================}
:CLS_PN             = JEDEC_TYPE | ALT_SYMBOLS  | DESCRIPTION                                                        | CPN_STATUS ;
{========================================================================================}
 'G220-10017-01'    = 'SC70_5V1' | '(SC70_5V1)' | 'IC,74LVC1G07,SINGLE BUFF/DRIVER WITH OD OUTPUT,SC70_5'            | ''        
 'G220-10088-01'    = 'SC70_5V1' | '(SC70_5V1)' | 'IC,Buffer,SN74LVC1G07DCKR,1.65-5.5V,G,SC70-5,SMD'                 | ''        
 'G223-10188-01'    = 'SOT353'   | '(SOT353)'   | 'IC,SINGLE NONINVERTING BUFFER,CMOS LOGICAL LEVEL SHIFTER,SOT-353' | ''        
 'G220-10015-01'    = 'SC70_5V1' | '(SC70_5V1)' | 'IC,74LVC1G14,SINGLE SCHMITT_INV,SC70'                             | ''        
 'A220-10088-IB'    = 'SC70_5V1' | '(SC70_5V1)' | 'IC,BUFFER,74LVC1G07,1.65-5.5V,-40~85C,TSSOP5,SMD'                 | ''        

END_PART

END.

